# S9S_MB_2U (Grand Teton) — schematic netlist excerpt (pin names and nets, part order shuffled) for the footprints in the layout excerpt that follows; sources: Cadence DE-HDL packaged netlist, KiCad conversion of 03242023_DA0F0TMBIJ0_F0T_Motherboard_J_brd_V01_OCP.brd

C874  Q_CAP_DIFFBUS  DIFF BUS_0.22UF 6.3V 20% X6S  pkg C0201  page 174 : \1\ = P5E_CPU0_PE3_TX_C_DN<13> ; \2\ = P5E_CPU0_PE3_TX_DN<13>
R3028  Q_RES  100K 1% EMPTY  pkg 0402LF  page 148 : A = FM_SMB_1_ALERT_GPU_N ; B = GND
R3973  Q_RES  0 5% CHIP  pkg 0402LF  page 192 : A = P3V3_E1S_PWRGD_0 ; B = TP_P3V3_E1S_PWRGD_0

(kicad_pcb
	(version 20260206)
	(generator "pcbnew")
	(generator_version "10.0")
	(general
		(thickness 1.6)
		(legacy_teardrops no)
	)
	(paper "A4")
	(title_block
		(title "03242023_DA0F0TMBIJ0_F0T_Motherboard_J_brd_V01_OCP.brd")
		(comment 1 "Grand Teton / footprints 4096-4098 of 6105")
	)
	(layers
		(0 "F.Cu" signal "TOP")
		(4 "In1.Cu" signal "GND")
		(6 "In2.Cu" signal "IN1")
		(8 "In3.Cu" signal "GND1")
		(10 "In4.Cu" signal "IN2")
		(12 "In5.Cu" signal "GND2")
		(14 "In6.Cu" signal "IN3")
		(16 "In7.Cu" signal "GND3")
		(18 "In8.Cu" signal "VCC")
		(20 "In9.Cu" signal "VCC1")
		(22 "In10.Cu" signal "GND4")
		(24 "In11.Cu" signal "IN4")
		(26 "In12.Cu" signal "GND5")
		(28 "In13.Cu" signal "IN5")
		(30 "In14.Cu" signal "GND6")
		(32 "In15.Cu" signal "IN6")
		(34 "In16.Cu" signal "GND7")
		(2 "B.Cu" signal "BOTTOM")
		(9 "F.Adhes" user "F.Adhesive")
		(11 "B.Adhes" user "B.Adhesive")
		(13 "F.Paste" user "Package Geometry/Pastemask Top")
		(15 "B.Paste" user "Package Geometry/Pastemask Bottom")
		(5 "F.SilkS" user "Ref Des/Silkscreen Top")
		(7 "B.SilkS" user "Ref Des/Silkscreen Bottom")
		(1 "F.Mask" user "Board Geometry/Soldermask Top")
		(3 "B.Mask" user "Board Geometry/Soldermask Bottom")
		(17 "Dwgs.User" user "User.Drawings")
		(19 "Cmts.User" user "User.Comments")
		(21 "Eco1.User" user "User.Eco1")
		(23 "Eco2.User" user "User.Eco2")
		(25 "Edge.Cuts" user "Board Geometry/Outline")
		(27 "Margin" user)
		(31 "F.CrtYd" user "Package Geometry/Place Bound Top")
		(29 "B.CrtYd" user "Package Geometry/Place Bound Bottom")
		(35 "F.Fab" user "Ref Des/Assembly Top")
		(33 "B.Fab" user "Ref Des/Assembly Bottom")
	)
	(footprint ""
		(layer "F.Cu")
		(at 224.771712 -67.921378)
		(property "Reference" "R3973"
			(at 0 0 0)
			(layer "F.SilkS")
			(hide yes)
			(effects
				(font
					(size 1.27 1.27)
				)
			)
		)
		(property "Value" ""
			(at 0 0 0)
			(layer "F.Fab")
			(effects
				(font
					(size 1.27 1.27)
				)
			)
		)
		(duplicate_pad_numbers_are_jumpers no)
		(fp_line
			(start -0.7874 -0.4064)
			(end 0.7874 -0.4064)
			(stroke
				(width 0.1524)
				(type default)
			)
			(layer "F.SilkS")
		)
		(fp_line
			(start -0.7874 0.4064)
			(end -0.7874 -0.4064)
			(stroke
				(width 0.1524)
				(type default)
			)
			(layer "F.SilkS")
		)
		(fp_line
			(start 0.7874 -0.4064)
			(end 0.7874 0.4064)
			(stroke
				(width 0.1524)
				(type default)
			)
			(layer "F.SilkS")
		)
		(fp_line
			(start 0.7874 0.4064)
			(end -0.7874 0.4064)
			(stroke
				(width 0.1524)
				(type default)
			)
			(layer "F.SilkS")
		)
		(fp_line
			(start -0.67945 -0.305054)
			(end -0.12065 -0.305054)
			(stroke
				(width 0.1)
				(type default)
			)
			(layer "F.Fab")
		)
		(fp_line
			(start -0.67945 0.3048)
			(end -0.67945 -0.305054)
			(stroke
				(width 0.1)
				(type default)
			)
			(layer "F.Fab")
		)
		(fp_line
			(start -0.12065 -0.305054)
			(end -0.12065 -0.2794)
			(stroke
				(width 0.1)
				(type default)
			)
			(layer "F.Fab")
		)
		(fp_line
			(start -0.12065 -0.2794)
			(end 0.12065 -0.2794)
			(stroke
				(width 0.1)
				(type default)
			)
			(layer "F.Fab")
		)
		(fp_line
			(start -0.12065 0.2794)
			(end -0.12065 0.3048)
			(stroke
				(width 0.1)
				(type default)
			)
			(layer "F.Fab")
		)
		(fp_line
			(start -0.12065 0.3048)
			(end -0.67945 0.3048)
			(stroke
				(width 0.1)
				(type default)
			)
			(layer "F.Fab")
		)
		(fp_line
			(start 0.120396 0.2794)
			(end -0.12065 0.2794)
			(stroke
				(width 0.1)
				(type default)
			)
			(layer "F.Fab")
		)
		(fp_line
			(start 0.120396 0.3048)
			(end 0.120396 0.2794)
			(stroke
				(width 0.1)
				(type default)
			)
			(layer "F.Fab")
		)
		(fp_line
			(start 0.12065 -0.3048)
			(end 0.67945 -0.3048)
			(stroke
				(width 0.1)
				(type default)
			)
			(layer "F.Fab")
		)
		(fp_line
			(start 0.12065 -0.2794)
			(end 0.12065 -0.3048)
			(stroke
				(width 0.1)
				(type default)
			)
			(layer "F.Fab")
		)
		(fp_line
			(start 0.67945 -0.3048)
			(end 0.67945 0.3048)
			(stroke
				(width 0.1)
				(type default)
			)
			(layer "F.Fab")
		)
		(fp_line
			(start 0.67945 0.3048)
			(end 0.120396 0.3048)
			(stroke
				(width 0.1)
				(type default)
			)
			(layer "F.Fab")
		)
		(pad "1" smd circle
			(at -0.40005 0)
			(size 0 0)
			(layers "F.Cu" "F.Mask" "F.Paste")
			(net "P3V3_E1S_PWRGD_0")
		)
		(pad "2" smd circle
			(at 0.40005 0)
			(size 0 0)
			(layers "F.Cu" "F.Mask" "F.Paste")
			(net "TP_P3V3_E1S_PWRGD_0")
		)
	)
	(footprint ""
		(layer "F.Cu")
		(at 117.86108 -400.414998 90)
		(property "Reference" "R3028"
			(at 0 0 90)
			(layer "F.SilkS")
			(hide yes)
			(effects
				(font
					(size 1.27 1.27)
				)
			)
		)
		(property "Value" ""
			(at 0 0 90)
			(layer "F.Fab")
			(effects
				(font
					(size 1.27 1.27)
				)
			)
		)
		(duplicate_pad_numbers_are_jumpers no)
		(fp_line
			(start 0.7874 -0.4064)
			(end 0.7874 0.4064)
			(stroke
				(width 0.1524)
				(type default)
			)
			(layer "F.SilkS")
		)
		(fp_line
			(start -0.7874 -0.4064)
			(end 0.7874 -0.4064)
			(stroke
				(width 0.1524)
				(type default)
			)
			(layer "F.SilkS")
		)
		(fp_line
			(start 0.7874 0.4064)
			(end -0.7874 0.4064)
			(stroke
				(width 0.1524)
				(type default)
			)
			(layer "F.SilkS")
		)
		(fp_line
			(start -0.7874 0.4064)
			(end -0.7874 -0.4064)
			(stroke
				(width 0.1524)
				(type default)
			)
			(layer "F.SilkS")
		)
		(fp_line
			(start -0.12065 -0.305054)
			(end -0.12065 -0.2794)
			(stroke
				(width 0.1)
				(type default)
			)
			(layer "F.Fab")
		)
		(fp_line
			(start -0.67945 -0.305054)
			(end -0.12065 -0.305054)
			(stroke
				(width 0.1)
				(type default)
			)
			(layer "F.Fab")
		)
		(fp_line
			(start 0.67945 -0.3048)
			(end 0.67945 0.3048)
			(stroke
				(width 0.1)
				(type default)
			)
			(layer "F.Fab")
		)
		(fp_line
			(start 0.12065 -0.3048)
			(end 0.67945 -0.3048)
			(stroke
				(width 0.1)
				(type default)
			)
			(layer "F.Fab")
		)
		(fp_line
			(start 0.12065 -0.2794)
			(end 0.12065 -0.3048)
			(stroke
				(width 0.1)
				(type default)
			)
			(layer "F.Fab")
		)
		(fp_line
			(start -0.12065 -0.2794)
			(end 0.12065 -0.2794)
			(stroke
				(width 0.1)
				(type default)
			)
			(layer "F.Fab")
		)
		(fp_line
			(start 0.120396 0.2794)
			(end -0.12065 0.2794)
			(stroke
				(width 0.1)
				(type default)
			)
			(layer "F.Fab")
		)
		(fp_line
			(start -0.12065 0.2794)
			(end -0.12065 0.3048)
			(stroke
				(width 0.1)
				(type default)
			)
			(layer "F.Fab")
		)
		(fp_line
			(start 0.67945 0.3048)
			(end 0.120396 0.3048)
			(stroke
				(width 0.1)
				(type default)
			)
			(layer "F.Fab")
		)
		(fp_line
			(start 0.120396 0.3048)
			(end 0.120396 0.2794)
			(stroke
				(width 0.1)
				(type default)
			)
			(layer "F.Fab")
		)
		(fp_line
			(start -0.12065 0.3048)
			(end -0.67945 0.3048)
			(stroke
				(width 0.1)
				(type default)
			)
			(layer "F.Fab")
		)
		(fp_line
			(start -0.67945 0.3048)
			(end -0.67945 -0.305054)
			(stroke
				(width 0.1)
				(type default)
			)
			(layer "F.Fab")
		)
		(pad "1" smd circle
			(at -0.40005 0 90)
			(size 0 0)
			(layers "F.Cu" "F.Mask" "F.Paste")
			(net "FM_SMB_1_ALERT_GPU_N")
		)
		(pad "2" smd circle
			(at 0.40005 0 90)
			(size 0 0)
			(layers "F.Cu" "F.Mask" "F.Paste")
			(net "GND")
		)
	)
	(footprint ""
		(layer "F.Cu")
		(at 378.87021 -408.517344 -90)
		(property "Reference" "C874"
			(at 0 0 270)
			(layer "F.SilkS")
			(hide yes)
			(effects
				(font
					(size 1.27 1.27)
				)
			)
		)
		(property "Value" ""
			(at 0 0 270)
			(layer "F.Fab")
			(effects
				(font
					(size 1.27 1.27)
				)
			)
		)
		(duplicate_pad_numbers_are_jumpers no)
		(fp_line
			(start -0.299974 0.150114)
			(end -0.299974 -0.150114)
			(stroke
				(width 0.1)
				(type default)
			)
			(layer "F.Fab")
		)
		(fp_line
			(start 0.299974 0.150114)
			(end -0.299974 0.150114)
			(stroke
				(width 0.1)
				(type default)
			)
			(layer "F.Fab")
		)
		(fp_line
			(start -0.299974 -0.150114)
			(end 0.299974 -0.150114)
			(stroke
				(width 0.1)
				(type default)
			)
			(layer "F.Fab")
		)
		(fp_line
			(start 0.299974 -0.150114)
			(end 0.299974 0.150114)
			(stroke
				(width 0.1)
				(type default)
			)
			(layer "F.Fab")
		)
		(pad "1" smd rect
			(at -0.2667 0 270)
			(size 0.3048 0.381)
			(layers "F.Cu" "F.Mask" "F.Paste")
			(net "P5E_CPU0_PE3_TX_C_DN<13>")
		)
		(pad "2" smd rect
			(at 0.2667 0 270)
			(size 0.3048 0.381)
			(layers "F.Cu" "F.Mask" "F.Paste")
			(net "P5E_CPU0_PE3_TX_DN<13>")
		)
	)
)
